# BASEBOARD_FAB2 (Tioga Pass) — schematic netlist excerpt (pin names and nets, part order shuffled) for the footprints in the layout excerpt that follows; sources: Cadence DE-HDL packaged netlist, KiCad conversion of Wiwynn_Tioga_Pass_MB.brd

C3M34  CAP  0.22UF 16V 10% X7R  pkg 0402  page 105 : A = P3E_CPU0_PE1_PCH_R_RXP<8> ; B = P3E_CPU0_PE1_PCH_RXP<8>
R7W8  RES  0.0 5% CHIP  pkg 0402  page 120 : A = FM_POST_CARD_PRES_BMC_N ; B = FM_POST_CARD_PRES_BMC_R1_N
R6U18  RES  665 1.0% CHIP  pkg 0402  page 99 : A = PVPP_GHJ ; B = SMB_DDR_GHJ_VPP_SDA_R

(kicad_pcb
	(version 20260206)
	(generator "pcbnew")
	(generator_version "10.0")
	(general
		(thickness 1.6)
		(legacy_teardrops no)
	)
	(paper "A4")
	(title_block
		(title "Wiwynn_Tioga_Pass_MB.brd")
		(comment 1 "Tioga Pass / footprints 2408-2410 of 4770")
	)
	(layers
		(0 "F.Cu" signal "TOP")
		(4 "In1.Cu" signal "L2GND")
		(6 "In2.Cu" signal "L3")
		(8 "In3.Cu" signal "L4GND")
		(10 "In4.Cu" signal "L5")
		(12 "In5.Cu" signal "L6GND")
		(14 "In6.Cu" signal "L7VCC")
		(16 "In7.Cu" signal "L8VCC")
		(18 "In8.Cu" signal "L9GND")
		(20 "In9.Cu" signal "L10")
		(22 "In10.Cu" signal "L11GND")
		(24 "In11.Cu" signal "L12")
		(26 "In12.Cu" signal "L13GND")
		(2 "B.Cu" signal "BOTTOM")
		(9 "F.Adhes" user "F.Adhesive")
		(11 "B.Adhes" user "B.Adhesive")
		(13 "F.Paste" user "Package Geometry/Pastemask Top")
		(15 "B.Paste" user "Package Geometry/Pastemask Bottom")
		(5 "F.SilkS" user "Ref Des/Silkscreen Top")
		(7 "B.SilkS" user "Ref Des/Silkscreen Bottom")
		(1 "F.Mask" user "Board Geometry/Soldermask Top")
		(3 "B.Mask" user "Board Geometry/Soldermask Bottom")
		(17 "Dwgs.User" user "User.Drawings")
		(19 "Cmts.User" user "User.Comments")
		(21 "Eco1.User" user "User.Eco1")
		(23 "Eco2.User" user "User.Eco2")
		(25 "Edge.Cuts" user "Board Geometry/Outline")
		(27 "Margin" user)
		(31 "F.CrtYd" user "Package Geometry/Place Bound Top")
		(29 "B.CrtYd" user "Package Geometry/Place Bound Bottom")
		(35 "F.Fab" user "Ref Des/Assembly Top")
		(33 "B.Fab" user "Ref Des/Assembly Bottom")
	)
	(footprint ""
		(layer "B.Cu")
		(at 400.756628 -117.179344)
		(property "Reference" "R7W8"
			(at 0.8382 -0.67818 0)
			(unlocked yes)
			(layer "B.SilkS")
			(effects
				(font
					(size 0.4064 0.254)
					(thickness 0.1524)
				)
				(justify left mirror)
			)
		)
		(property "Value" ""
			(at 0 0 0)
			(layer "B.Fab")
			(effects
				(font
					(size 1.27 1.27)
				)
				(justify mirror)
			)
		)
		(duplicate_pad_numbers_are_jumpers no)
		(fp_poly
			(pts
				(xy 0.2794 -0.1016) (xy -0.2794 -0.1016) (xy -0.2794 0.9906) (xy 0.2794 0.9906)
			)
			(stroke
				(width 0)
				(type default)
			)
			(fill no)
			(layer "B.CrtYd")
		)
		(fp_line
			(start -0.2794 -0.1016)
			(end 0.2794 -0.1016)
			(stroke
				(width 0.1)
				(type default)
			)
			(layer "B.Fab")
		)
		(fp_line
			(start -0.2794 0.9906)
			(end -0.2794 -0.1016)
			(stroke
				(width 0.1)
				(type default)
			)
			(layer "B.Fab")
		)
		(fp_line
			(start 0.2794 -0.1016)
			(end 0.2794 0.9906)
			(stroke
				(width 0.1)
				(type default)
			)
			(layer "B.Fab")
		)
		(fp_line
			(start 0.2794 0.9906)
			(end -0.2794 0.9906)
			(stroke
				(width 0.1)
				(type default)
			)
			(layer "B.Fab")
		)
		(pad "1" smd rect
			(at 0 0 180)
			(size 0.508 0.508)
			(layers "B.Cu" "B.Mask" "B.Paste")
			(net "FM_POST_CARD_PRES_BMC_N")
		)
		(pad "2" smd rect
			(at 0 0.889 180)
			(size 0.508 0.508)
			(layers "B.Cu" "B.Mask" "B.Paste")
			(net "FM_POST_CARD_PRES_BMC_R1_N")
		)
		(zone
			(layer "B.Cu")
			(hatch none 0.5)
			(connect_pads
				(clearance 0)
			)
			(min_thickness 0.25)
			(keepout
				(tracks allowed)
				(vias not_allowed)
				(pads allowed)
				(copperpour not_allowed)
				(footprints allowed)
			)
			(placement
				(enabled no)
				(sheetname "")
			)
			(fill
				(thermal_gap 0.5)
				(thermal_bridge_width 0.5)
				(island_removal_mode 0)
			)
			(polygon
				(pts
					(xy 401.010628 -116.925344) (xy 400.502628 -116.925344) (xy 400.502628 -116.544344) (xy 401.010628 -116.544344)
				)
			)
		)
		(zone
			(layer "B.Cu")
			(hatch none 0.5)
			(connect_pads
				(clearance 0)
			)
			(min_thickness 0.25)
			(keepout
				(tracks not_allowed)
				(vias allowed)
				(pads allowed)
				(copperpour not_allowed)
				(footprints allowed)
			)
			(placement
				(enabled no)
				(sheetname "")
			)
			(fill
				(thermal_gap 0.5)
				(thermal_bridge_width 0.5)
				(island_removal_mode 0)
			)
			(polygon
				(pts
					(xy 401.010628 -116.544344) (xy 400.502628 -116.544344) (xy 400.502628 -116.925344) (xy 401.010628 -116.925344)
				)
			)
		)
	)
	(footprint ""
		(layer "B.Cu")
		(at 165.9001 4.445 180)
		(property "Reference" "R6U18"
			(at 0 0 0)
			(layer "B.SilkS")
			(hide yes)
			(effects
				(font
					(size 1.27 1.27)
				)
				(justify mirror)
			)
		)
		(property "Value" ""
			(at 0 0 0)
			(layer "B.Fab")
			(effects
				(font
					(size 1.27 1.27)
				)
				(justify mirror)
			)
		)
		(duplicate_pad_numbers_are_jumpers no)
		(fp_poly
			(pts
				(xy 0.2794 -0.1016) (xy -0.2794 -0.1016) (xy -0.2794 0.9906) (xy 0.2794 0.9906)
			)
			(stroke
				(width 0)
				(type default)
			)
			(fill no)
			(layer "B.CrtYd")
		)
		(fp_line
			(start 0.2794 0.9906)
			(end -0.2794 0.9906)
			(stroke
				(width 0.1)
				(type default)
			)
			(layer "B.Fab")
		)
		(fp_line
			(start 0.2794 -0.1016)
			(end 0.2794 0.9906)
			(stroke
				(width 0.1)
				(type default)
			)
			(layer "B.Fab")
		)
		(fp_line
			(start -0.2794 0.9906)
			(end -0.2794 -0.1016)
			(stroke
				(width 0.1)
				(type default)
			)
			(layer "B.Fab")
		)
		(fp_line
			(start -0.2794 -0.1016)
			(end 0.2794 -0.1016)
			(stroke
				(width 0.1)
				(type default)
			)
			(layer "B.Fab")
		)
		(pad "1" smd rect
			(at 0 0)
			(size 0.508 0.508)
			(layers "B.Cu" "B.Mask" "B.Paste")
			(net "PVPP_GHJ")
		)
		(pad "2" smd rect
			(at 0 0.889)
			(size 0.508 0.508)
			(layers "B.Cu" "B.Mask" "B.Paste")
			(net "SMB_DDR_GHJ_VPP_SDA_R")
		)
		(zone
			(layer "B.Cu")
			(hatch none 0.5)
			(connect_pads
				(clearance 0)
			)
			(min_thickness 0.25)
			(keepout
				(tracks not_allowed)
				(vias allowed)
				(pads allowed)
				(copperpour not_allowed)
				(footprints allowed)
			)
			(placement
				(enabled no)
				(sheetname "")
			)
			(fill
				(thermal_gap 0.5)
				(thermal_bridge_width 0.5)
				(island_removal_mode 0)
			)
			(polygon
				(pts
					(xy 165.6461 3.81) (xy 166.1541 3.81) (xy 166.1541 4.191) (xy 165.6461 4.191)
				)
			)
		)
		(zone
			(layer "B.Cu")
			(hatch none 0.5)
			(connect_pads
				(clearance 0)
			)
			(min_thickness 0.25)
			(keepout
				(tracks allowed)
				(vias not_allowed)
				(pads allowed)
				(copperpour not_allowed)
				(footprints allowed)
			)
			(placement
				(enabled no)
				(sheetname "")
			)
			(fill
				(thermal_gap 0.5)
				(thermal_bridge_width 0.5)
				(island_removal_mode 0)
			)
			(polygon
				(pts
					(xy 165.6461 4.191) (xy 166.1541 4.191) (xy 166.1541 3.81) (xy 165.6461 3.81)
				)
			)
		)
	)
	(footprint ""
		(layer "B.Cu")
		(at 368.709956 -121.443242 -90)
		(property "Reference" "C3M34"
			(at 0 0 90)
			(layer "B.SilkS")
			(hide yes)
			(effects
				(font
					(size 1.27 1.27)
				)
				(justify mirror)
			)
		)
		(property "Value" ""
			(at 0 0 90)
			(layer "B.Fab")
			(effects
				(font
					(size 1.27 1.27)
				)
				(justify mirror)
			)
		)
		(duplicate_pad_numbers_are_jumpers no)
		(fp_poly
			(pts
				(xy -0.3048 -0.1016) (xy -0.3048 0.9906) (xy 0.3048 0.9906) (xy 0.3048 -0.1016)
			)
			(stroke
				(width 0)
				(type default)
			)
			(fill no)
			(layer "B.CrtYd")
		)
		(fp_line
			(start -0.3048 0.9906)
			(end -0.3048 -0.1016)
			(stroke
				(width 0.1)
				(type default)
			)
			(layer "B.Fab")
		)
		(fp_line
			(start 0.3048 0.9906)
			(end -0.3048 0.9906)
			(stroke
				(width 0.1)
				(type default)
			)
			(layer "B.Fab")
		)
		(fp_line
			(start -0.3048 -0.1016)
			(end 0.3048 -0.1016)
			(stroke
				(width 0.1)
				(type default)
			)
			(layer "B.Fab")
		)
		(fp_line
			(start 0.3048 -0.1016)
			(end 0.3048 0.9906)
			(stroke
				(width 0.1)
				(type default)
			)
			(layer "B.Fab")
		)
		(pad "1" smd rect
			(at 0 0 90)
			(size 0.508 0.508)
			(layers "B.Cu" "B.Mask" "B.Paste")
			(net "P3E_CPU0_PE1_PCH_R_RXP<8>")
		)
		(pad "2" smd rect
			(at 0 0.889 90)
			(size 0.508 0.508)
			(layers "B.Cu" "B.Mask" "B.Paste")
			(net "P3E_CPU0_PE1_PCH_RXP<8>")
		)
		(zone
			(layer "B.Cu")
			(hatch none 0.5)
			(connect_pads
				(clearance 0)
			)
			(min_thickness 0.25)
			(keepout
				(tracks not_allowed)
				(vias allowed)
				(pads allowed)
				(copperpour not_allowed)
				(footprints allowed)
			)
			(placement
				(enabled no)
				(sheetname "")
			)
			(fill
				(thermal_gap 0.5)
				(thermal_bridge_width 0.5)
				(island_removal_mode 0)
			)
			(polygon
				(pts
					(xy 368.074956 -121.189242) (xy 368.074956 -121.697242) (xy 368.455956 -121.697242) (xy 368.455956 -121.189242)
				)
			)
		)
		(zone
			(layer "B.Cu")
			(hatch none 0.5)
			(connect_pads
				(clearance 0)
			)
			(min_thickness 0.25)
			(keepout
				(tracks allowed)
				(vias not_allowed)
				(pads allowed)
				(copperpour not_allowed)
				(footprints allowed)
			)
			(placement
				(enabled no)
				(sheetname "")
			)
			(fill
				(thermal_gap 0.5)
				(thermal_bridge_width 0.5)
				(island_removal_mode 0)
			)
			(polygon
				(pts
					(xy 368.455956 -121.189242) (xy 368.455956 -121.697242) (xy 368.074956 -121.697242) (xy 368.074956 -121.189242)
				)
			)
		)
	)
)
